(kicad_pcb
	(version 20260206)
	(generator "pcbnew")
	(generator_version "10.0")
	(general
		(thickness 1.6)
		(legacy_teardrops no)
	)
	(paper "A4")
	(title_block
		(title "panther-plus-userver — 13130-1b_20150205.brd")
		(comment 1 "Honey Badger (Wiwynn) / footprints 1087-1095 of 1509")
	)
	(layers
		(0 "F.Cu" signal "TOP")
		(4 "In1.Cu" signal "L2")
		(6 "In2.Cu" signal "L3")
		(8 "In3.Cu" signal "L4")
		(10 "In4.Cu" signal "L5")
		(12 "In5.Cu" signal "L6")
		(14 "In6.Cu" signal "L7")
		(16 "In7.Cu" signal "L8")
		(18 "In8.Cu" signal "L9")
		(20 "In9.Cu" signal "L10")
		(22 "In10.Cu" signal "L11")
		(2 "B.Cu" signal "BOTTOM")
		(9 "F.Adhes" user "F.Adhesive")
		(11 "B.Adhes" user "B.Adhesive")
		(13 "F.Paste" user "Package Geometry/Pastemask Top")
		(15 "B.Paste" user "Package Geometry/Pastemask Bottom")
		(5 "F.SilkS" user "Ref Des/Silkscreen Top")
		(7 "B.SilkS" user "Ref Des/Silkscreen Bottom")
		(1 "F.Mask" user "Board Geometry/Soldermask Top")
		(3 "B.Mask" user "Board Geometry/Soldermask Bottom")
		(17 "Dwgs.User" user "User.Drawings")
		(19 "Cmts.User" user "User.Comments")
		(21 "Eco1.User" user "User.Eco1")
		(23 "Eco2.User" user "User.Eco2")
		(25 "Edge.Cuts" user "Board Geometry/Outline")
		(27 "Margin" user)
		(31 "F.CrtYd" user "Package Geometry/Place Bound Top")
		(29 "B.CrtYd" user "Package Geometry/Place Bound Bottom")
		(35 "F.Fab" user "Ref Des/Assembly Top")
		(33 "B.Fab" user "Ref Des/Assembly Bottom")
	)
	(footprint ""
		(layer "B.Cu")
		(at 201.2696 -31.496 90)
		(property "Reference" "LED5"
			(at 0 0 90)
			(layer "B.SilkS")
			(hide yes)
			(effects
				(font
					(size 1.27 1.27)
				)
				(justify mirror)
			)
		)
		(property "Value" "LED-YG-51-GP"
			(at 0.0381 -2.6162 90)
			(unlocked yes)
			(layer "B.Fab")
			(hide yes)
			(effects
				(font
					(size 1.016 1.016)
					(thickness 0.1524)
				)
				(justify mirror)
			)
		)
		(property "Device Type" "LED1608AKH40"
			(at 0.0381 -4.1402 90)
			(unlocked yes)
			(layer "B.Fab")
			(hide yes)
			(effects
				(font
					(size 1.016 1.016)
					(thickness 0.1524)
				)
				(justify mirror)
			)
		)
		(duplicate_pad_numbers_are_jumpers no)
		(fp_line
			(start 0.5334 1.3081)
			(end -0.5334 1.3081)
			(stroke
				(width 0.254)
				(type default)
			)
			(layer "B.SilkS")
		)
		(fp_rect
			(start 0.6604 1.1811)
			(end -0.6604 -1.1811)
			(stroke
				(width 0)
				(type default)
			)
			(fill no)
			(layer "B.CrtYd")
		)
		(fp_rect
			(start 0.6604 1.1811)
			(end -0.6604 -1.1811)
			(stroke
				(width 0)
				(type default)
			)
			(fill no)
			(layer "B.Fab")
		)
		(pad "A" smd rect
			(at 0 -0.652526 270)
			(size 1.0668 0.8128)
			(layers "B.Cu" "B.Mask" "B.Paste")
			(net "PORT80_R_BIT0")
		)
		(pad "K" smd rect
			(at 0 0.652526 270)
			(size 1.0668 0.8128)
			(layers "B.Cu" "B.Mask" "B.Paste")
			(net "PORT80_BIT0")
		)
	)
	(footprint ""
		(layer "B.Cu")
		(at 67.437 -17.78 90)
		(property "Reference" "PR180"
			(at 0 0 90)
			(layer "B.SilkS")
			(hide yes)
			(effects
				(font
					(size 1.27 1.27)
				)
				(justify mirror)
			)
		)
		(property "Value" "0R2J-2-GP"
			(at -1.7907 -1.1176 90)
			(unlocked yes)
			(layer "B.Fab")
			(hide yes)
			(effects
				(font
					(size 1.016 1.016)
					(thickness 0.1524)
				)
				(justify mirror)
			)
		)
		(property "Device Type" "R402H16"
			(at -1.7907 -2.6416 90)
			(unlocked yes)
			(layer "B.Fab")
			(hide yes)
			(effects
				(font
					(size 1.016 1.016)
					(thickness 0.1524)
				)
				(justify mirror)
			)
		)
		(duplicate_pad_numbers_are_jumpers no)
		(fp_rect
			(start 0.381 0.8382)
			(end -0.381 -0.8382)
			(stroke
				(width 0)
				(type default)
			)
			(fill no)
			(layer "B.CrtYd")
		)
		(fp_rect
			(start 0.381 0.8382)
			(end -0.381 -0.8382)
			(stroke
				(width 0)
				(type default)
			)
			(fill no)
			(layer "B.Fab")
		)
		(pad "1" smd custom
			(at 0 -0.4318 270)
			(size 0.127 0.127)
			(layers "B.Cu" "B.Mask" "B.Paste")
			(net "VR_FB_R_P1V8_STBY")
			(options
				(clearance outline)
				(anchor circle)
			)
			(primitives
				(gr_poly
					(pts
						(arc
							(start -0.2032 0.2794)
							(mid -0.239121 0.264521)
							(end -0.254 0.2286)
						)
						(arc
							(start -0.254 -0.2286)
							(mid -0.239121 -0.264521)
							(end -0.2032 -0.2794)
						)
						(arc
							(start 0.2032 -0.2794)
							(mid 0.239121 -0.264521)
							(end 0.254 -0.2286)
						)
						(arc
							(start 0.254 0.2286)
							(mid 0.239121 0.264521)
							(end 0.2032 0.2794)
						)
					)
					(width 0)
					(fill yes)
				)
			)
		)
		(pad "2" smd custom
			(at 0 0.4318 270)
			(size 0.127 0.127)
			(layers "B.Cu" "B.Mask" "B.Paste")
			(net "P1V8_STBY_VOUT")
			(options
				(clearance outline)
				(anchor circle)
			)
			(primitives
				(gr_poly
					(pts
						(arc
							(start -0.2032 0.2794)
							(mid -0.239121 0.264521)
							(end -0.254 0.2286)
						)
						(arc
							(start -0.254 -0.2286)
							(mid -0.239121 -0.264521)
							(end -0.2032 -0.2794)
						)
						(arc
							(start 0.2032 -0.2794)
							(mid 0.239121 -0.264521)
							(end 0.254 -0.2286)
						)
						(arc
							(start 0.254 0.2286)
							(mid 0.239121 0.264521)
							(end 0.2032 0.2794)
						)
					)
					(width 0)
					(fill yes)
				)
			)
		)
	)
	(footprint ""
		(layer "B.Cu")
		(at 77.343 -56.007)
		(property "Reference" "C71"
			(at 0 0 0)
			(layer "B.SilkS")
			(hide yes)
			(effects
				(font
					(size 1.27 1.27)
				)
				(justify mirror)
			)
		)
		(property "Value" "SCD1U16V2KX-3GP"
			(at -1.1811 -2.7051 0)
			(unlocked yes)
			(layer "B.Fab")
			(hide yes)
			(effects
				(font
					(size 1.016 1.016)
					(thickness 0.1524)
				)
				(justify mirror)
			)
		)
		(property "Device Type" "C402H22"
			(at -1.1811 -4.2291 0)
			(unlocked yes)
			(layer "B.Fab")
			(hide yes)
			(effects
				(font
					(size 1.016 1.016)
					(thickness 0.1524)
				)
				(justify mirror)
			)
		)
		(duplicate_pad_numbers_are_jumpers no)
		(fp_rect
			(start 0.381 0.7366)
			(end -0.381 -0.7366)
			(stroke
				(width 0)
				(type default)
			)
			(fill no)
			(layer "B.CrtYd")
		)
		(fp_rect
			(start 0.381 0.7366)
			(end -0.381 -0.7366)
			(stroke
				(width 0)
				(type default)
			)
			(fill no)
			(layer "B.Fab")
		)
		(pad "1" smd custom
			(at 0 -0.4572 180)
			(size 0.1143 0.1143)
			(layers "B.Cu" "B.Mask" "B.Paste")
			(net "P3V3_STBY")
			(options
				(clearance outline)
				(anchor circle)
			)
			(primitives
				(gr_poly
					(pts
						(arc
							(start -0.254 0.1778)
							(mid -0.239121 0.213721)
							(end -0.2032 0.2286)
						)
						(arc
							(start 0.2032 0.2286)
							(mid 0.239121 0.213721)
							(end 0.254 0.1778)
						)
						(arc
							(start 0.254 -0.1778)
							(mid 0.239121 -0.213721)
							(end 0.2032 -0.2286)
						)
						(arc
							(start -0.2032 -0.2286)
							(mid -0.239121 -0.213721)
							(end -0.254 -0.1778)
						)
					)
					(width 0)
					(fill yes)
				)
			)
		)
		(pad "2" smd custom
			(at 0 0.4572 180)
			(size 0.1143 0.1143)
			(layers "B.Cu" "B.Mask" "B.Paste")
			(net "GND")
			(options
				(clearance outline)
				(anchor circle)
			)
			(primitives
				(gr_poly
					(pts
						(arc
							(start -0.254 0.1778)
							(mid -0.239121 0.213721)
							(end -0.2032 0.2286)
						)
						(arc
							(start 0.2032 0.2286)
							(mid 0.239121 0.213721)
							(end 0.254 0.1778)
						)
						(arc
							(start 0.254 -0.1778)
							(mid 0.239121 -0.213721)
							(end 0.2032 -0.2286)
						)
						(arc
							(start -0.2032 -0.2286)
							(mid -0.239121 -0.213721)
							(end -0.254 -0.1778)
						)
					)
					(width 0)
					(fill yes)
				)
			)
		)
	)
	(footprint ""
		(layer "B.Cu")
		(at 130.429 -31.115 90)
		(property "Reference" "C140"
			(at 0 0 90)
			(layer "B.SilkS")
			(hide yes)
			(effects
				(font
					(size 1.27 1.27)
				)
				(justify mirror)
			)
		)
		(property "Value" "SCD1U10V2KX-5GP"
			(at -1.1811 -2.7051 90)
			(unlocked yes)
			(layer "B.Fab")
			(hide yes)
			(effects
				(font
					(size 1.016 1.016)
					(thickness 0.1524)
				)
				(justify mirror)
			)
		)
		(property "Device Type" "C402H22"
			(at -1.1811 -4.2291 90)
			(unlocked yes)
			(layer "B.Fab")
			(hide yes)
			(effects
				(font
					(size 1.016 1.016)
					(thickness 0.1524)
				)
				(justify mirror)
			)
		)
		(duplicate_pad_numbers_are_jumpers no)
		(fp_rect
			(start 0.381 0.7366)
			(end -0.381 -0.7366)
			(stroke
				(width 0)
				(type default)
			)
			(fill no)
			(layer "B.CrtYd")
		)
		(fp_rect
			(start 0.381 0.7366)
			(end -0.381 -0.7366)
			(stroke
				(width 0)
				(type default)
			)
			(fill no)
			(layer "B.Fab")
		)
		(pad "1" smd custom
			(at 0 -0.4572 270)
			(size 0.1143 0.1143)
			(layers "B.Cu" "B.Mask" "B.Paste")
			(net "P3V3_STBY")
			(options
				(clearance outline)
				(anchor circle)
			)
			(primitives
				(gr_poly
					(pts
						(arc
							(start -0.254 0.1778)
							(mid -0.239121 0.213721)
							(end -0.2032 0.2286)
						)
						(arc
							(start 0.2032 0.2286)
							(mid 0.239121 0.213721)
							(end 0.254 0.1778)
						)
						(arc
							(start 0.254 -0.1778)
							(mid 0.239121 -0.213721)
							(end 0.2032 -0.2286)
						)
						(arc
							(start -0.2032 -0.2286)
							(mid -0.239121 -0.213721)
							(end -0.254 -0.1778)
						)
					)
					(width 0)
					(fill yes)
				)
			)
		)
		(pad "2" smd custom
			(at 0 0.4572 270)
			(size 0.1143 0.1143)
			(layers "B.Cu" "B.Mask" "B.Paste")
			(net "GND")
			(options
				(clearance outline)
				(anchor circle)
			)
			(primitives
				(gr_poly
					(pts
						(arc
							(start -0.254 0.1778)
							(mid -0.239121 0.213721)
							(end -0.2032 0.2286)
						)
						(arc
							(start 0.2032 0.2286)
							(mid 0.239121 0.213721)
							(end 0.254 0.1778)
						)
						(arc
							(start 0.254 -0.1778)
							(mid 0.239121 -0.213721)
							(end 0.2032 -0.2286)
						)
						(arc
							(start -0.2032 -0.2286)
							(mid -0.239121 -0.213721)
							(end -0.254 -0.1778)
						)
					)
					(width 0)
					(fill yes)
				)
			)
		)
	)
	(footprint ""
		(layer "B.Cu")
		(at 89.535 -44.577 180)
		(property "Reference" "C160"
			(at 0 0 0)
			(layer "B.SilkS")
			(hide yes)
			(effects
				(font
					(size 1.27 1.27)
				)
				(justify mirror)
			)
		)
		(property "Value" "SC1U10V2KX-1GP"
			(at -1.1811 -2.7051 180)
			(unlocked yes)
			(layer "B.Fab")
			(hide yes)
			(effects
				(font
					(size 1.016 1.016)
					(thickness 0.1524)
				)
				(justify mirror)
			)
		)
		(property "Device Type" "C402H22"
			(at -1.1811 -4.2291 180)
			(unlocked yes)
			(layer "B.Fab")
			(hide yes)
			(effects
				(font
					(size 1.016 1.016)
					(thickness 0.1524)
				)
				(justify mirror)
			)
		)
		(duplicate_pad_numbers_are_jumpers no)
		(fp_rect
			(start 0.381 0.7366)
			(end -0.381 -0.7366)
			(stroke
				(width 0)
				(type default)
			)
			(fill no)
			(layer "B.CrtYd")
		)
		(fp_rect
			(start 0.381 0.7366)
			(end -0.381 -0.7366)
			(stroke
				(width 0)
				(type default)
			)
			(fill no)
			(layer "B.Fab")
		)
		(pad "1" smd custom
			(at 0 -0.4572)
			(size 0.1143 0.1143)
			(layers "B.Cu" "B.Mask" "B.Paste")
			(net "P1V8_STBY")
			(options
				(clearance outline)
				(anchor circle)
			)
			(primitives
				(gr_poly
					(pts
						(arc
							(start -0.254 0.1778)
							(mid -0.239121 0.213721)
							(end -0.2032 0.2286)
						)
						(arc
							(start 0.2032 0.2286)
							(mid 0.239121 0.213721)
							(end 0.254 0.1778)
						)
						(arc
							(start 0.254 -0.1778)
							(mid 0.239121 -0.213721)
							(end 0.2032 -0.2286)
						)
						(arc
							(start -0.2032 -0.2286)
							(mid -0.239121 -0.213721)
							(end -0.254 -0.1778)
						)
					)
					(width 0)
					(fill yes)
				)
			)
		)
		(pad "2" smd custom
			(at 0 0.4572)
			(size 0.1143 0.1143)
			(layers "B.Cu" "B.Mask" "B.Paste")
			(net "GND")
			(options
				(clearance outline)
				(anchor circle)
			)
			(primitives
				(gr_poly
					(pts
						(arc
							(start -0.254 0.1778)
							(mid -0.239121 0.213721)
							(end -0.2032 0.2286)
						)
						(arc
							(start 0.2032 0.2286)
							(mid 0.239121 0.213721)
							(end 0.254 0.1778)
						)
						(arc
							(start 0.254 -0.1778)
							(mid 0.239121 -0.213721)
							(end 0.2032 -0.2286)
						)
						(arc
							(start -0.2032 -0.2286)
							(mid -0.239121 -0.213721)
							(end -0.254 -0.1778)
						)
					)
					(width 0)
					(fill yes)
				)
			)
		)
	)
	(footprint ""
		(layer "B.Cu")
		(at 188.7728 -11.812778 -90)
		(property "Reference" "R196"
			(at 0 0 90)
			(layer "B.SilkS")
			(hide yes)
			(effects
				(font
					(size 1.27 1.27)
				)
				(justify mirror)
			)
		)
		(property "Value" "4K7R2F-GP"
			(at -0.064008 -3.993896 270)
			(unlocked yes)
			(layer "B.Fab")
			(hide yes)
			(effects
				(font
					(size 1.016 1.016)
					(thickness 0.1524)
				)
				(justify mirror)
			)
		)
		(property "Device Type" "R402H16"
			(at -0.064008 -5.517896 270)
			(unlocked yes)
			(layer "B.Fab")
			(hide yes)
			(effects
				(font
					(size 1.016 1.016)
					(thickness 0.1524)
				)
				(justify mirror)
			)
		)
		(duplicate_pad_numbers_are_jumpers no)
		(fp_rect
			(start 0.381 0.8382)
			(end -0.381 -0.8382)
			(stroke
				(width 0)
				(type default)
			)
			(fill no)
			(layer "B.CrtYd")
		)
		(fp_rect
			(start 0.381 0.8382)
			(end -0.381 -0.8382)
			(stroke
				(width 0)
				(type default)
			)
			(fill no)
			(layer "B.Fab")
		)
		(pad "1" smd custom
			(at 0 -0.4318 90)
			(size 0.127 0.127)
			(layers "B.Cu" "B.Mask" "B.Paste")
			(net "P3V3_STBY")
			(options
				(clearance outline)
				(anchor circle)
			)
			(primitives
				(gr_poly
					(pts
						(arc
							(start -0.2032 0.2794)
							(mid -0.239121 0.264521)
							(end -0.254 0.2286)
						)
						(arc
							(start -0.254 -0.2286)
							(mid -0.239121 -0.264521)
							(end -0.2032 -0.2794)
						)
						(arc
							(start 0.2032 -0.2794)
							(mid 0.239121 -0.264521)
							(end 0.254 -0.2286)
						)
						(arc
							(start 0.254 0.2286)
							(mid 0.239121 0.264521)
							(end 0.2032 0.2794)
						)
					)
					(width 0)
					(fill yes)
				)
			)
		)
		(pad "2" smd custom
			(at 0 0.4318 90)
			(size 0.127 0.127)
			(layers "B.Cu" "B.Mask" "B.Paste")
			(net "CHB_0_SA0")
			(options
				(clearance outline)
				(anchor circle)
			)
			(primitives
				(gr_poly
					(pts
						(arc
							(start -0.2032 0.2794)
							(mid -0.239121 0.264521)
							(end -0.254 0.2286)
						)
						(arc
							(start -0.254 -0.2286)
							(mid -0.239121 -0.264521)
							(end -0.2032 -0.2794)
						)
						(arc
							(start 0.2032 -0.2794)
							(mid 0.239121 -0.264521)
							(end 0.254 -0.2286)
						)
						(arc
							(start 0.254 0.2286)
							(mid 0.239121 0.264521)
							(end 0.2032 0.2794)
						)
					)
					(width 0)
					(fill yes)
				)
			)
		)
	)
	(footprint ""
		(layer "B.Cu")
		(at 100.457 -57.785 90)
		(property "Reference" "R259"
			(at 0 0 90)
			(layer "B.SilkS")
			(hide yes)
			(effects
				(font
					(size 1.27 1.27)
				)
				(justify mirror)
			)
		)
		(property "Value" "0R2J-2-GP"
			(at -0.064008 -3.993896 90)
			(unlocked yes)
			(layer "B.Fab")
			(hide yes)
			(effects
				(font
					(size 1.016 1.016)
					(thickness 0.1524)
				)
				(justify mirror)
			)
		)
		(property "Device Type" "R402H16"
			(at -0.064008 -5.517896 90)
			(unlocked yes)
			(layer "B.Fab")
			(hide yes)
			(effects
				(font
					(size 1.016 1.016)
					(thickness 0.1524)
				)
				(justify mirror)
			)
		)
		(duplicate_pad_numbers_are_jumpers no)
		(fp_rect
			(start 0.381 0.8382)
			(end -0.381 -0.8382)
			(stroke
				(width 0)
				(type default)
			)
			(fill no)
			(layer "B.CrtYd")
		)
		(fp_rect
			(start 0.381 0.8382)
			(end -0.381 -0.8382)
			(stroke
				(width 0)
				(type default)
			)
			(fill no)
			(layer "B.Fab")
		)
		(pad "1" smd custom
			(at 0 -0.4318 270)
			(size 0.127 0.127)
			(layers "B.Cu" "B.Mask" "B.Paste")
			(net "M_A_RESET#")
			(options
				(clearance outline)
				(anchor circle)
			)
			(primitives
				(gr_poly
					(pts
						(arc
							(start -0.2032 0.2794)
							(mid -0.239121 0.264521)
							(end -0.254 0.2286)
						)
						(arc
							(start -0.254 -0.2286)
							(mid -0.239121 -0.264521)
							(end -0.2032 -0.2794)
						)
						(arc
							(start 0.2032 -0.2794)
							(mid 0.239121 -0.264521)
							(end 0.254 -0.2286)
						)
						(arc
							(start 0.254 0.2286)
							(mid 0.239121 0.264521)
							(end 0.2032 0.2794)
						)
					)
					(width 0)
					(fill yes)
				)
			)
		)
		(pad "2" smd custom
			(at 0 0.4318 270)
			(size 0.127 0.127)
			(layers "B.Cu" "B.Mask" "B.Paste")
			(net "M_A_R_RESET#")
			(options
				(clearance outline)
				(anchor circle)
			)
			(primitives
				(gr_poly
					(pts
						(arc
							(start -0.2032 0.2794)
							(mid -0.239121 0.264521)
							(end -0.254 0.2286)
						)
						(arc
							(start -0.254 -0.2286)
							(mid -0.239121 -0.264521)
							(end -0.2032 -0.2794)
						)
						(arc
							(start 0.2032 -0.2794)
							(mid 0.239121 -0.264521)
							(end 0.254 -0.2286)
						)
						(arc
							(start 0.254 0.2286)
							(mid 0.239121 0.264521)
							(end 0.2032 0.2794)
						)
					)
					(width 0)
					(fill yes)
				)
			)
		)
	)
	(footprint ""
		(layer "B.Cu")
		(at 75.819 -32.893)
		(property "Reference" "TP46"
			(at 0 0 0)
			(layer "B.SilkS")
			(hide yes)
			(effects
				(font
					(size 1.27 1.27)
				)
				(justify mirror)
			)
		)
		(property "Value" "TPAD24"
			(at 0 -2.9972 0)
			(unlocked yes)
			(layer "B.Fab")
			(hide yes)
			(effects
				(font
					(size 1.016 1.016)
					(thickness 0.1524)
				)
				(justify mirror)
			)
		)
		(property "Device Type" "TPAD24"
			(at 0 -4.5212 0)
			(unlocked yes)
			(layer "B.Fab")
			(hide yes)
			(effects
				(font
					(size 1.016 1.016)
					(thickness 0.1524)
				)
				(justify mirror)
			)
		)
		(duplicate_pad_numbers_are_jumpers no)
		(fp_poly
			(pts
				(arc
					(start 0.3048 0)
					(mid -0.3048 0)
					(end 0.3048 0)
				)
			)
			(stroke
				(width 0)
				(type default)
			)
			(fill no)
			(layer "B.CrtYd")
		)
		(fp_poly
			(pts
				(arc
					(start 0.6096 0)
					(mid -0.6096 0)
					(end 0.6096 0)
				)
			)
			(stroke
				(width 0)
				(type default)
			)
			(fill no)
			(layer "B.Fab")
		)
		(pad "1" smd circle
			(at 0 0 180)
			(size 0.6096 0.6096)
			(layers "B.Cu" "B.Mask" "B.Paste")
			(net "GBE_MDIO_DATA0")
		)
	)
	(footprint ""
		(layer "B.Cu")
		(at 75.438 -52.324)
		(property "Reference" "R260"
			(at 0 0 0)
			(layer "B.SilkS")
			(hide yes)
			(effects
				(font
					(size 1.27 1.27)
				)
				(justify mirror)
			)
		)
		(property "Value" "240R3-GP"
			(at 0.0254 -2.5146 0)
			(unlocked yes)
			(layer "B.Fab")
			(hide yes)
			(effects
				(font
					(size 1.016 1.016)
					(thickness 0.1524)
				)
				(justify mirror)
			)
		)
		(property "Device Type" "R603H22"
			(at 0.0254 -4.0386 0)
			(unlocked yes)
			(layer "B.Fab")
			(hide yes)
			(effects
				(font
					(size 1.016 1.016)
					(thickness 0.1524)
				)
				(justify mirror)
			)
		)
		(duplicate_pad_numbers_are_jumpers no)
		(fp_line
			(start -0.4318 0)
			(end -0.2032 0)
			(stroke
				(width 0.2032)
				(type default)
			)
			(layer "B.SilkS")
		)
		(fp_line
			(start 0.2032 0)
			(end 0.4191 0)
			(stroke
				(width 0.2032)
				(type default)
			)
			(layer "B.SilkS")
		)
		(fp_rect
			(start 0.635 1.1811)
			(end -0.635 -1.1811)
			(stroke
				(width 0)
				(type default)
			)
			(fill no)
			(layer "B.CrtYd")
		)
		(fp_rect
			(start 0.635 1.1811)
			(end -0.635 -1.1811)
			(stroke
				(width 0)
				(type default)
			)
			(fill no)
			(layer "B.Fab")
		)
		(pad "1" smd custom
			(at 0 -0.6604 180)
			(size 0.19685 0.19685)
			(layers "B.Cu" "B.Mask" "B.Paste")
			(net "P1V0")
			(options
				(clearance outline)
				(anchor circle)
			)
			(primitives
				(gr_poly
					(pts
						(arc
							(start 0.508 0.2921)
							(mid 0.478242 0.363942)
							(end 0.4064 0.3937)
						)
						(arc
							(start -0.4064 0.3937)
							(mid -0.478242 0.363942)
							(end -0.508 0.2921)
						)
						(arc
							(start -0.508 -0.2921)
							(mid -0.478242 -0.363942)
							(end -0.4064 -0.3937)
						)
						(arc
							(start 0.4064 -0.3937)
							(mid 0.478242 -0.363942)
							(end 0.508 -0.2921)
						)
					)
					(width 0)
					(fill yes)
				)
			)
		)
		(pad "2" smd custom
			(at 0 0.6604 180)
			(size 0.19685 0.19685)
			(layers "B.Cu" "B.Mask" "B.Paste")
			(net "MEMORY_CPU_HOT#")
			(options
				(clearance outline)
				(anchor circle)
			)
			(primitives
				(gr_poly
					(pts
						(arc
							(start 0.508 0.2921)
							(mid 0.478242 0.363942)
							(end 0.4064 0.3937)
						)
						(arc
							(start -0.4064 0.3937)
							(mid -0.478242 0.363942)
							(end -0.508 0.2921)
						)
						(arc
							(start -0.508 -0.2921)
							(mid -0.478242 -0.363942)
							(end -0.4064 -0.3937)
						)
						(arc
							(start 0.4064 -0.3937)
							(mid 0.478242 -0.363942)
							(end 0.508 -0.2921)
						)
					)
					(width 0)
					(fill yes)
				)
			)
		)
	)
)
